FILE_TYPE = CONNECTIVITY;
{Allegro Design Entry HDL 16.6-p007 (v16-6-112F) 10/10/2012}
"PAGE_NUMBER" = 231;
0"NC";
1"PVPP_ABC\g";
2"GND\g";
3"AGND_PVPP_ABC\g";
4"GND\g";
5"GND\g";
6"GND\g";
7"GND\g";
8"P12V_STBY\g";
9"AGND_PVPP_ABC\g";
10"GND\g";
11"AGND_PVPP_ABC\g";
12"GND\g";
13"GND\g";
14"GND\g";
15"GND\g";
16"GND\g";
17"PVPP_ABC\g";
18"AGND_PVPP_ABC\g";
19"AGND_PVPP_ABC\g";
20"P3V3_STBY\g";
21"AGND_PVPP_ABC\g";
22"GND\g";
23"AGND_PVPP_ABC\g";
24"AGND_PVPP_ABC\g";
25"GND\g";
26"GND\g";
27"GND\g";
28"GND\g";
29"GND\g";
30"FM_PVPP_CPU0_EN";
31"VR_PVPP_ABC_PHASE";
32"VR_PVPP_ABC_BOOT";
33"VR_PVPP_ABC_BOOT_R";
34"VSENSE_PVPP_ABC";
35"VR_COMP_PVPP_ABC";
36"VR_FB_PVPP_ABC";
37"VR_COMP_RC_PVPP_ABC";
38"VR_PVPP_ABC_SNUB";
39"VR_COMP_PVPP_ABC_3";
40"PWRGD_PVPP_ABC";
41"PWRGD_PVPP_ABC_R";
42"VR_FET_SW_P12V_STBY_PVPP_ABC";
43"VR_VB_PVPP_ABC";
44"VR_PVPP_ABC_ISET";
45"VR_PVPP_ABC_SS";
46"FM_PVPP_PVDDQ_CPU0_EN_ABC";
%"CAP"
"1","(-7850,1000)","0","mstr_discrete","I122";
;
ROOM"PVPP_KLM_VR"
BOM_COST"MEM_VRD_PVPP_AB"
$SEC"1"
CDS_SEC"1"
CDS_LOCATION"C6F6"
VOLTAGE"4V"
CDS_LIB"mstr_discrete"
LOCATION"C6F6"
VALUE"10UF"
PART_NUMBER"E15431-001"
PACK_TYPE"0603LF"
TOLERANCE"20%"
MATERIAL"X6S";
"A"
$PN"1"1;
"B"
$PN"2"5;
%"PVPP_ABC"
"1","(-7850,1275)","0","mstr_symbols","I123";
;
ROOM"PVPP_KLM_VR"
HDL_POWER"PVPP_ABC"
BOM_COST"MEM_VRD_PVPP_AB"
CDS_LIB"mstr_symbols"
BODY_TYPE"PLUMBING"
VOLTAGE"2.5V";
"G\NAC"1;
%"CAP"
"1","(-7600,1000)","0","mstr_discrete","I124";
;
BOM_COST"MEM_VRD_PVPP_AB"
CDS_SEC"1"
$SEC"1"
CDS_LOCATION"C4T6"
ROOM"PVPP_KLM_VR"
VOLTAGE"4V"
CDS_LIB"mstr_discrete"
LOCATION"C4T6"
VALUE"10UF"
PART_NUMBER"E15431-001"
PACK_TYPE"0603LF"
MATERIAL"X6S"
TOLERANCE"20%";
"A"
$PN"1"1;
"B"
$PN"2"5;
%"CAP"
"1","(-7325,1000)","0","mstr_discrete","I125";
;
BOM_COST"MEM_VRD_PVPP_AB"
$SEC"1"
CDS_SEC"1"
ROOM"PVPP_KLM_VR"
CDS_LOCATION"C4T5"
VOLTAGE"4V"
CDS_LIB"mstr_discrete"
LOCATION"C4T5"
PART_NUMBER"E15431-001"
VALUE"10UF"
PACK_TYPE"0603LF"
MATERIAL"X6S"
TOLERANCE"20%";
"A"
$PN"1"1;
"B"
$PN"2"5;
%"CAP"
"1","(-7075,975)","0","mstr_discrete","I126";
;
BOM_COST"MEM_VRD_PVPP_AB"
CDS_SEC"1"
$SEC"1"
CDS_LOCATION"C6G1"
ROOM"PVPP_KLM_VR"
CDS_LIB"mstr_discrete"
VOLTAGE"4V"
LOCATION"C6G1"
VALUE"10UF"
PART_NUMBER"E15431-001"
PACK_TYPE"0603LF"
MATERIAL"X6S"
TOLERANCE"20%";
"A"
$PN"1"1;
"B"
$PN"2"5;
%"GND"
"1","(-6625,2200)","0","mstr_symbols","I127";
;
HDL_POWER"GND"
VOLTAGE"0"
SIZE"1B"
CDS_LIB"mstr_symbols"
BODY_TYPE"PLUMBING"
BOM_COST"PVPP_KLM_VR"
BOM"SYSB_CPLD"
ROOM"PVPP_KLM_VR";
"A\NAC"2;
%"CAP"
"1","(-6800,1000)","0","mstr_discrete","I128";
;
BOM_COST"MEM_VRD_PVPP_AB"
CDS_SEC"1"
$SEC"1"
CDS_LOCATION"C6G2"
ROOM"PVPP_KLM_VR"
VOLTAGE"4V"
CDS_LIB"mstr_discrete"
LOCATION"C6G2"
VALUE"10UF"
PART_NUMBER"E15431-001"
PACK_TYPE"0603LF"
MATERIAL"X6S"
TOLERANCE"20%";
"A"
$PN"1"1;
"B"
$PN"2"5;
%"CAP"
"1","(-6500,1000)","0","mstr_discrete","I129";
;
$SEC"1"
CDS_SEC"1"
ROOM"PVPP_KLM_VR"
BOM_COST"MEM_VRD_PVPP_AB"
CDS_LOCATION"C4U2"
VOLTAGE"4V"
CDS_LIB"mstr_discrete"
LOCATION"C4U2"
VALUE"10UF"
PART_NUMBER"E15431-001"
TOLERANCE"20%"
PACK_TYPE"0603LF"
MATERIAL"X6S";
"A"
$PN"1"1;
"B"
$PN"2"5;
%"CAP"
"1","(-6225,1000)","0","mstr_discrete","I130";
;
$SEC"1"
CDS_SEC"1"
ROOM"PVPP_KLM_VR"
BOM_COST"MEM_VRD_PVPP_AB"
CDS_LOCATION"C4U1"
VOLTAGE"4V"
CDS_LIB"mstr_discrete"
LOCATION"C4U1"
PART_NUMBER"E15431-001"
VALUE"10UF"
TOLERANCE"20%"
PACK_TYPE"0603LF"
MATERIAL"X6S";
"A"
$PN"1"1;
"B"
$PN"2"5;
%"CAP"
"1","(-5925,1000)","0","mstr_discrete","I131";
;
BOM_COST"MEM_VRD_PVPP_AB"
CDS_SEC"1"
$SEC"1"
CDS_LOCATION"C6G4"
ROOM"PVPP_KLM_VR"
VOLTAGE"4V"
CDS_LIB"mstr_discrete"
LOCATION"C6G4"
VALUE"10UF"
PART_NUMBER"E15431-001"
TOLERANCE"20%"
PACK_TYPE"0603LF"
MATERIAL"X6S";
"A"
$PN"1"1;
"B"
$PN"2"5;
%"AGND_SCSI"
"1","(-6175,2325)","0","mstr_symbols","I132";
;
CDS_LIB"mstr_symbols"
BOM_COST"PVPP_KLM_VR"
ROOM"PVPP_KLM_VR"
BODY_TYPE"PLUMBING"
VOLTAGE"0.0V"
HDL_POWER"AGND_PVPP_ABC";
"A"3;
%"RES"
"2","(-4400,1900)","2","mstr_discrete","I134";
;
CDS_SEC"1"
$SEC"1"
CDS_LOCATION"R7F15"
CDS_LIB"mstr_discrete"
BOM_COST"PVPP_KLM_VR"
ROOM"PVPP_KLM_VR"
LOCATION"R7F15"
VALUE"7.87K"
TOLERANCE"1.0%"
MATERIAL"CHIP"
WATTAGE"1/16W"
PACK_TYPE"0402"
PART_NUMBER"G21796-242";
"A"
$PN"1"44;
"B"
$PN"2"19;
%"RES"
"2","(-6625,2450)","0","mstr_discrete","I136";
;
BOM"SYSB_CPLD"
BOM_COST"PVPP_KLM_VR"
CDS_SEC"1"
$SEC"1"
CDS_LOCATION"R7F14"
ROOM"PVPP_KLM_VR"
CDS_LIB"mstr_discrete"
LOCATION"R7F14"
PART_NUMBER"G21796-016"
VALUE"10.0K"
WATTAGE"1/16W"
MATERIAL"CHIP"
TOLERANCE"1%"
PACK_TYPE"0402";
"A"
$PN"1"30;
"B"
$PN"2"2;
%"CAP"
"1","(-6175,2650)","2","mstr_discrete","I140";
;
FIN"VR_1P2"
REUSE_ID"1"
CDS_SEC"1"
$SEC"1"
CDS_LOCATION"C7F8"
CDS_LIB"mstr_discrete"
BOM_COST"PVPP_KLM_VR"
ROOM"PVPP_KLM_VR"
LOCATION"C7F8"
VALUE"1000PF"
TOLERANCE"10%"
VOLTAGE"50V"
MATERIAL"EMPTY"
PACK_TYPE"0402LF"
PART_NUMBER"A36096-046";
"A"
$PN"1"30;
"B"
$PN"2"3;
%"GND"
"1","(-3525,725)","0","mstr_symbols","I141";
;
HDL_POWER"GND"
CDS_LIB"mstr_symbols"
VOLTAGE"0"
SIZE"1B"
BODY_TYPE"PLUMBING"
BOM_COST"PVPP_KLM_VR"
ROOM"PVPP_KLM_VR";
"A\NAC"4;
%"CAP"
"1","(-3525,975)","0","mstr_discrete","I142";
;
REUSE_ID"17"
CDS_SEC"1"
$SEC"1"
CDS_LOCATION"C7F11"
BOM_COST"PVPP_KLM_VR"
CDS_LIB"mstr_discrete"
ROOM"PVPP_KLM_VR"
VALUE"1000PF"
LOCATION"C7F11"
PART_NUMBER"A36096-046"
PACK_TYPE"0402LF"
TOLERANCE"10%"
VOLTAGE"50V"
MATERIAL"X7R";
"A"
$PN"1"41;
"B"
$PN"2"4;
%"RES"
"2","(-3875,1500)","0","mstr_discrete","I143";
;
CDS_SEC"1"
SEC_TYPE"0402"
BOM_COST"PVPP_KLM_VR"
REUSE_ID"21"
SEC"1"
CDS_LOCATION"R7F19"
ROOM"PVPP_KLM_VR"
CDS_LIB"mstr_discrete"
PART_NUMBER"G21796-026"
LOCATION"R7F19"
VALUE"1.00K"
TOLERANCE"1%"
WATTAGE"1/16W"
MATERIAL"CHIP"
PACK_TYPE"0402";
"A"
$PN"1"20;
"B"
$PN"2"41;
%"CAP"
"1","(-5625,1000)","0","mstr_discrete","I145";
;
BOM_COST"MEM_VRD_PVPP_AB"
CDS_SEC"1"
$SEC"1"
CDS_LOCATION"C6G5"
ROOM"PVPP_KLM_VR"
VOLTAGE"4V"
CDS_LIB"mstr_discrete"
LOCATION"C6G5"
VALUE"10UF"
PART_NUMBER"E15431-001"
TOLERANCE"20%"
PACK_TYPE"0603LF"
MATERIAL"X6S";
"A"
$PN"1"1;
"B"
$PN"2"5;
%"CAP"
"1","(-5350,975)","0","mstr_discrete","I146";
;
CDS_SEC"1"
$SEC"1"
BOM_COST"MEM_VRD_PVPP_AB"
ROOM"PVPP_KLM_VR"
CDS_LOCATION"C4U4"
CDS_LIB"mstr_discrete"
VOLTAGE"4V"
PART_NUMBER"E15431-001"
VALUE"10UF"
LOCATION"C4U4"
MATERIAL"X6S"
PACK_TYPE"0603LF"
TOLERANCE"20%";
"A"
$PN"1"1;
"B"
$PN"2"5;
%"GND"
"1","(-4900,675)","0","mstr_symbols","I147";
;
SIZE"1B"
HDL_POWER"GND"
VOLTAGE"0"
CDS_LIB"mstr_symbols"
BODY_TYPE"PLUMBING"
BOM_COST"MEM_VRD_PVPP_AB"
ROOM"PVPP_KLM_VR";
"A\NAC"5;
%"CAP"
"1","(-5075,975)","0","mstr_discrete","I148";
;
$SEC"1"
CDS_SEC"1"
ROOM"PVPP_KLM_VR"
BOM_COST"MEM_VRD_PVPP_AB"
CDS_LOCATION"C4U3"
CDS_LIB"mstr_discrete"
VOLTAGE"4V"
LOCATION"C4U3"
VALUE"10UF"
PART_NUMBER"E15431-001"
PACK_TYPE"0603LF"
TOLERANCE"20%"
MATERIAL"X6S";
"A"
$PN"1"1;
"B"
$PN"2"5;
%"CAP"
"1","(-4825,1000)","0","mstr_discrete","I149";
;
CDS_SEC"1"
BOM_COST"MEM_VRD_PVPP_AB"
SEC_TYPE"0603LF"
SEC"1"
CDS_LOCATION"C6F5"
ROOM"PVPP_KLM_VR"
VOLTAGE"4V"
CDS_LIB"mstr_discrete"
LOCATION"C6F5"
VALUE"10UF"
PART_NUMBER"E15431-001"
PACK_TYPE"0603LF"
TOLERANCE"20%"
MATERIAL"X6S";
"A"
$PN"1"1;
"B"
$PN"2"5;
%"CAP"
"1","(-6600,4375)","0","mstr_discrete","I151";
;
CDS_SEC"1"
$SEC"1"
CDS_LOCATION"C7F7"
BOM_COST"PVPP_KLM_VR"
CDS_LIB"mstr_discrete"
ROOM"PVPP_KLM_VR"
PART_NUMBER"D38464-007"
VOLTAGE"16V"
VALUE"47UF"
LOCATION"C7F7"
MATERIAL"X6S"
TOLERANCE"20%"
PACK_TYPE"1210";
"A"
$PN"1"42;
"B"
$PN"2"6;
%"GND"
"1","(-6600,4200)","0","mstr_symbols","I152";
;
HDL_POWER"GND"
SIZE"1B"
BODY_TYPE"PLUMBING"
CDS_LIB"mstr_symbols"
VOLTAGE"0"
BOM_COST"PVPP_KLM_VR"
ROOM"PVPP_KLM_VR";
"A\NAC"6;
%"RES"
"1","(-3725,4450)","0","mstr_discrete","I154";
;
REUSE_ID"13"
CDS_SEC"1"
$SEC"1"
SPOF"TRUE"
CDS_LIB"mstr_discrete"
BOM_COST"PVPP_ABC_VR"
CDS_LOCATION"R7F8"
ROOM"PVPP_ABC_VR"
PACK_TYPE"0402"
LOCATION"R7F8"
TOLERANCE"5%"
MATERIAL"CHIP"
PART_NUMBER"G21497-005"
VALUE"0.0"
WATTAGE"1/16W";
"B"
$PN"2"33;
"A"
$PN"1"32;
%"CAP"
"2","(-3025,4450)","2","mstr_discrete","I159";
;
$SEC"1"
BOM_COST"PVPP_KLM_VR"
SPOF"TRUE"
CDS_SEC"1"
REUSE_ID"27"
CDS_LOCATION"C7F4"
ROOM"PVPP_KLM_VR"
CDS_LIB"mstr_discrete"
VALUE"0.1UF"
TOLERANCE"10%"
LOCATION"C7F4"
PART_NUMBER"602433-020"
PACK_TYPE"0603LF"
VOLTAGE"25V"
MATERIAL"X7R";
"A"
$PN"1"31;
"B"
$PN"2"33;
%"GND"
"1","(-4600,4075)","0","mstr_symbols","I160";
;
HDL_POWER"GND"
ROOM"PVPP_KLM_VR"
BOM_COST"PVPP_KLM_VR"
VOLTAGE"0"
CDS_LIB"mstr_symbols"
SIZE"1B"
BODY_TYPE"PLUMBING";
"A\NAC"7;
%"CAP"
"1","(-4600,4400)","0","mstr_discrete","I161";
;
FIN"VR_1P2"
$SEC"1"
CDS_SEC"1"
REUSE_ID"1"
ROOM"PVPP_KLM_VR"
BOM_COST"PVPP_KLM_VR"
CDS_LOCATION"C3T10"
CDS_LIB"mstr_discrete"
PART_NUMBER"D97712-011"
LOCATION"C3T10"
VALUE"1.0UF"
VOLTAGE"16V"
TOLERANCE"10%"
PACK_TYPE"0402"
MATERIAL"X6S";
"A"
$PN"1"42;
"B"
$PN"2"7;
%"FERRITE"
"1","(-6950,4550)","0","mstr_discrete","I162";
;
CDS_SEC"1"
SEC_TYPE"SM"
TOLERANCE"1%"
SEC"1"
ROOM"PVPP_KLM_VR"
CDS_LOCATION"FB7F1"
CDS_LIB"mstr_discrete"
PART_NUMBER"656554-051"
LOCATION"FB7F1"
PACK_TYPE"SM"
MATERIAL"FB"
VALUE"22";
"A"
$PN"1"8;
"B"
$PN"2"42;
%"P12V_STBY"
"1","(-7200,4825)","0","mstr_symbols","I163";
;
SIZE"1B"
VOLTAGE"12.0V"
CDS_LIB"mstr_symbols"
BODY_TYPE"PLUMBING"
HDL_POWER"P12V_STBY";
"G\NAC"8;
%"AGND_SCSI"
"1","(-1000,1425)","0","mstr_symbols","I165";
;
CDS_LIB"mstr_symbols"
VOLTAGE"0.0V"
BOM_COST"PVPP_KLM_VR"
BODY_TYPE"PLUMBING"
ROOM"PVPP_KLM_VR"
HDL_POWER"AGND_PVPP_ABC";
"A"9;
%"RES"
"2","(-1000,1800)","0","mstr_discrete","I166";
;
SPOF"TRUE"
REUSE_ID"7"
CDS_SEC"1"
$SEC"1"
CDS_LOCATION"R7F11"
CDS_LIB"mstr_discrete"
BOM_COST"PVPP_KLM_VR"
ROOM"PVPP_KLM_VR"
PART_NUMBER"G21796-146"
LOCATION"R7F11"
VALUE"6.34K"
TOLERANCE"1%"
WATTAGE"1/16W"
PACK_TYPE"0402"
MATERIAL"CHIP";
"A"
$PN"1"36;
"B"
$PN"2"9;
%"RES"
"2","(-1000,2425)","0","mstr_discrete","I167";
;
SPOF"TRUE"
REUSE_ID"9"
BOM_COST"PVPP_KLM_VR"
CDS_SEC"1"
$SEC"1"
ROOM"PVPP_KLM_VR"
CDS_LOCATION"R7F13"
CDS_LIB"mstr_discrete"
LOCATION"R7F13"
PART_NUMBER"G21796-040"
VALUE"20.0K"
PACK_TYPE"0402"
WATTAGE"1/16W"
TOLERANCE"1%"
MATERIAL"CHIP";
"A"
$PN"1"34;
"B"
$PN"2"36;
%"RES"
"1","(-1000,3175)","5","mstr_discrete","I168";
;
CDS_SEC"1"
SEC"1"
SPOF"TRUE"
SEC_TYPE"0402"
ROOM"PVPP_KLM_VR"
CDS_LIB"mstr_discrete"
CDS_LOCATION"R7F12"
LOCATION"R7F12"
WATTAGE"1/16W"
MATERIAL"CHIP"
VALUE"0.0"
TOLERANCE"5%"
PART_NUMBER"G21497-005"
PACK_TYPE"0402";
"B"
$PN"2"34;
"A"
$PN"1"17;
%"GND"
"1","(-1250,625)","0","mstr_symbols","I169";
;
HDL_POWER"GND"
CDS_LIB"mstr_symbols"
SIZE"1B"
VOLTAGE"0"
BODY_TYPE"PLUMBING"
ROOM"PVPP_KLM_VR"
BOM_COST"PVPP_KLM_VR";
"A\NAC"10;
%"RES"
"1","(-950,725)","0","mstr_discrete","I170";
;
CDS_LOCATION"R7F35"
ROOM"PVPP_KLM_VR"
$SEC"1"
CDS_SEC"1"
CDS_LIB"mstr_discrete"
LOCATION"R7F35"
MATERIAL"CHIP"
TOLERANCE"5%"
PART_NUMBER"G21497-005"
VALUE"0.0"
PACK_TYPE"0402"
WATTAGE"1/16W";
"B"
$PN"2"11;
"A"
$PN"1"10;
%"AGND_SCSI"
"1","(-700,625)","0","mstr_symbols","I171";
;
VOLTAGE"0.0V"
CDS_LIB"mstr_symbols"
BODY_TYPE"PLUMBING"
BOM_COST"PVPP_KLM_VR"
ROOM"PVPP_KLM_VR"
HDL_POWER"AGND_PVPP_ABC";
"A"11;
%"GND"
"1","(-2300,3400)","0","mstr_symbols","I173";
;
HDL_POWER"GND"
VOLTAGE"0"
CDS_LIB"mstr_symbols"
SIZE"1B"
BODY_TYPE"PLUMBING"
ROOM"PVPP_KLM_VR"
BOM_COST"PVPP_KLM_VR";
"A\NAC"12;
%"RES"
"2","(-2300,3600)","0","mstr_discrete","I174";
;
REUSE_ID"29"
CDS_SEC"1"
$SEC"1"
BOM_COST"PVPP_KLM_VR"
ROOM"PVPP_KLM_VR"
CDS_LOCATION"R7F7"
CDS_LIB"mstr_discrete"
MATERIAL"EMPTY"
PART_NUMBER"G21497-016"
WATTAGE"1/16W"
LOCATION"R7F7"
VALUE"2.2"
TOLERANCE"5%"
PACK_TYPE"0402";
"A"
$PN"1"38;
"B"
$PN"2"12;
%"CAP"
"1","(-2300,3950)","0","mstr_discrete","I175";
;
BOM_COST"PVPP_KLM_VR"
REUSE_ID"26"
CDS_SEC"1"
$SEC"1"
ROOM"PVPP_KLM_VR"
CDS_LOCATION"C7F3"
CDS_LIB"mstr_discrete"
MATERIAL"EMPTY"
PART_NUMBER"A36096-091"
VALUE"3300PF"
PACK_TYPE"0402LF"
TOLERANCE"10%"
VOLTAGE"50V"
LOCATION"C7F3";
"A"
$PN"1"31;
"B"
$PN"2"38;
%"GND"
"1","(-1725,3675)","0","mstr_symbols","I176";
;
HDL_POWER"GND"
SIZE"1B"
BODY_TYPE"PLUMBING"
CDS_LIB"mstr_symbols"
VOLTAGE"0"
ROOM"PVPP_KLM_VR"
BOM_COST"PVPP_KLM_VR";
"A\NAC"13;
%"RES"
"2","(-1725,3925)","0","mstr_discrete","I177";
;
CDS_SEC"1"
SEC_TYPE"0603"
BOM_COST"PVPP_KLM_VR"
REUSE_ID"34"
SEC"1"
ROOM"PVPP_KLM_VR"
CDS_LOCATION"R7F10"
CDS_LIB"mstr_discrete"
LOCATION"R7F10"
PART_NUMBER"G22026-003"
VALUE"120.0"
WATTAGE"1/10W"
MATERIAL"CHIP"
TOLERANCE"1%"
PACK_TYPE"0603";
"A"
$PN"1"17;
"B"
$PN"2"13;
%"INDUCTOR"
"1","(-1950,4100)","0","mstr_discrete","I178";
;
ROOM"PVPP_KLM_VR"
CDS_LOCATION"L7F1"
BOM_COST"PVPP_KLM_VR"
CDS_LIB"mstr_discrete"
REUSE_ID"30"
CDS_SEC"1"
$SEC"1"
TOLERANCE"1%"
PACK_TYPE"SM"
LOCATION"L7F1"
PART_NUMBER"E13358-018"
VALUE"0.47UH"
MATERIAL"IND";
"INA\NAC"
$PN"1"31;
"INB\NAC"
$PN"2"17;
%"GND"
"1","(-1400,3625)","0","mstr_symbols","I179";
;
HDL_POWER"GND"
VOLTAGE"0"
CDS_LIB"mstr_symbols"
SIZE"1B"
BODY_TYPE"PLUMBING"
ROOM"PVPP_KLM_VR"
BOM_COST"PVPP_KLM_VR";
"A\NAC"14;
%"CAPP"
"1","(-1400,3925)","0","mstr_discrete","I180";
;
REUSE_ID"28"
CDS_SEC"1"
$SEC"1"
CDS_LOCATION"C6F4"
ROOM"PVPP_KLM_VR"
BOM_COST"PVPP_KLM_VR"
CDS_LIB"mstr_discrete"
LOCATION"C6F4"
PART_NUMBER"724613-042"
VALUE"330UF"
TOLERANCE"20%"
PACK_TYPE"7343LF"
VOLTAGE"6.3V"
MATERIAL"POSCAP";
"B"
$PN"2"14;
"A"
$PN"1"17;
%"GND"
"1","(-825,3650)","0","mstr_symbols","I183";
;
SIZE"1B"
HDL_POWER"GND"
VOLTAGE"0"
CDS_LIB"mstr_symbols"
BODY_TYPE"PLUMBING"
ROOM"PVPP_KLM_VR"
BOM_COST"PVPP_KLM_VR";
"A\NAC"15;
%"CAP"
"1","(-825,3925)","0","mstr_discrete","I184";
;
$SEC"1"
CDS_SEC"1"
REUSE_ID"33"
CDS_LOCATION"C3T7"
CDS_LIB"mstr_discrete"
BOM_COST"PVPP_KLM_VR"
ROOM"PVPP_KLM_VR"
PART_NUMBER"C95333-006"
LOCATION"C3T7"
VALUE"47UF"
TOLERANCE"20%"
PACK_TYPE"0805"
VOLTAGE"4V"
MATERIAL"X6S";
"A"
$PN"1"17;
"B"
$PN"2"15;
%"GND"
"1","(-525,3650)","0","mstr_symbols","I185";
;
SIZE"1B"
BODY_TYPE"PLUMBING"
CDS_LIB"mstr_symbols"
VOLTAGE"0"
HDL_POWER"GND"
ROOM"PVPP_KLM_VR"
BOM_COST"PVPP_KLM_VR";
"A\NAC"16;
%"CAP"
"1","(-525,3925)","0","mstr_discrete","I186";
;
$SEC"1"
CDS_SEC"1"
REUSE_ID"33"
CDS_LOCATION"C3T9"
ROOM"PVPP_KLM_VR"
CDS_LIB"mstr_discrete"
BOM_COST"PVPP_KLM_VR"
LOCATION"C3T9"
PART_NUMBER"C95333-006"
VALUE"47UF"
TOLERANCE"20%"
PACK_TYPE"0805"
VOLTAGE"4V"
MATERIAL"X6S";
"A"
$PN"1"17;
"B"
$PN"2"16;
%"PVPP_ABC"
"1","(-450,4225)","0","mstr_symbols","I187";
;
ROOM"PVPP_KLM_VR"
BOM_COST"PVPP_KLM_VR"
HDL_POWER"PVPP_ABC"
CDS_LIB"mstr_symbols"
BODY_TYPE"PLUMBING"
VOLTAGE"2.5V";
"G\NAC"17;
%"AGND_SCSI"
"1","(-4025,2100)","0","mstr_symbols","I189";
;
CDS_LIB"mstr_symbols"
VOLTAGE"0.0V"
BODY_TYPE"PLUMBING"
BOM_COST"PVPP_KLM_VR"
ROOM"PVPP_KLM_VR"
HDL_POWER"AGND_PVPP_ABC";
"A"18;
%"AGND_SCSI"
"1","(-4400,1600)","0","mstr_symbols","I190";
;
VOLTAGE"0"
CDS_LIB"mstr_symbols"
BODY_TYPE"PLUMBING"
HDL_POWER"AGND_PVPP_ABC";
"A"19;
%"P3V3_STBY"
"1","(-3875,1775)","0","mstr_symbols","I192";
;
SIZE"1B"
VOLTAGE"+3.3V"
BODY_TYPE"PLUMBING"
CDS_LIB"mstr_symbols"
HDL_POWER"P3V3_STBY";
"G\NAC"20;
%"NCP3232L"
"1","(-3450,3125)","0","mstr_vreg","I193";
;
CDS_SEC"1"
SEC_TYPE"SM"
PACK_TYPE"SM"
SEC"1"
CDS_LOCATION"EU7F1"
CDS_LIB"mstr_vreg"
CDS_LMAN_SYM_OUTLINE"-450,850,450,-900"
LOCATION"EU7F1"
MATERIAL"IC"
PART_NUMBER"H86355-001";
"PG"
$PN"7"41;
"PGND<0>"
$PN"16"22;
"PGND<1>"
$PN"17"22;
"PGND<2>"
$PN"18"22;
"PGND<3>"
$PN"19"22;
"PGND<4>"
$PN"20"22;
"PGND<5>"
$PN"21"22;
"PGND<6>"
$PN"22"22;
"PGND<8>"
$PN"24"22;
"PGND<7>"
$PN"23"22;
"PGND<9>"
$PN"25"22;
"PGND<10>"
$PN"26"22;
"PGND<11>"
$PN"27"22;
"PGND<12>"
$PN"28"22;
"PGND<13>"
$PN"37"22;
"GND"
$PN"41"22;
"AGND"
$PN"5"18;
"EN"
$PN"40"46;
"SS"
$PN"1"45;
"ISET"
$PN"4"44;
"OTS"
$PN"6"24;
"VIN<6>"
$PN"14"42;
"VIN<7>"
$PN"42"42;
"VCC"
$PN"39"42;
"VIN<1>"
$PN"9"42;
"VIN<5>"
$PN"13"42;
"VIN<4>"
$PN"12"42;
"VIN<3>"
$PN"11"42;
"VIN<2>"
$PN"10"42;
"VIN<0>"
$PN"8"42;
"VB"
$PN"38"43;
"COMP"
$PN"3"39;
"FB"
$PN"2"36;
"VSWH<1>"
$PN"29"31;
"VSWH<0>"
$PN"15"31;
"VSW"
$PN"35"31;
"VSWH<2>"
$PN"30"31;
"VSWH<3>"
$PN"31"31;
"VSWH<4>"
$PN"32"31;
"VSWH<5>"
$PN"33"31;
"VSWH<6>"
$PN"34"31;
"BST"
$PN"36"32;
"VSWH<7>"
$PN"43"31;
%"CAP"
"1","(-4725,2425)","0","mstr_discrete","I194";
;
CDS_SEC"1"
SEC"1"
SEC_TYPE"0402"
REUSE_ID"26"
BOM_COST"PVPP_KLM_VR"
ROOM"PVPP_KLM_VR"
CDS_LIB"mstr_discrete"
CDS_LOCATION"C7F10"
LOCATION"C7F10"
PART_NUMBER"A36096-129"
VALUE"0.027UF"
TOLERANCE"10%"
PACK_TYPE"0402"
VOLTAGE"16V"
MATERIAL"X7R";
"A"
$PN"1"45;
"B"
$PN"2"21;
%"AGND_SCSI"
"1","(-4725,2200)","0","mstr_symbols","I195";
;
VOLTAGE"0.0V"
CDS_LIB"mstr_symbols"
BODY_TYPE"PLUMBING"
BOM_COST"PVPP_KLM_VR"
ROOM"PVPP_KLM_VR"
HDL_POWER"AGND_PVPP_ABC";
"A"21;
%"GND"
"1","(-2725,2175)","0","mstr_symbols","I196";
;
HDL_POWER"GND"
SIZE"1B"
VOLTAGE"0"
CDS_LIB"mstr_symbols"
BODY_TYPE"PLUMBING"
ROOM"PVPP_KLM_VR"
BOM_COST"PVPP_KLM_VR";
"A\NAC"22;
%"CAP"
"2","(-2075,3075)","2","mstr_discrete","I199";
;
CDS_SEC"1"
SEC_TYPE"0402LF"
REUSE_ID"27"
SEC"1"
CDS_LIB"mstr_discrete"
BOM_COST"PVPP_KLM_VR"
CDS_LOCATION"C7F9"
ROOM"PVPP_KLM_VR"
MATERIAL"COG"
TOLERANCE"5%"
LOCATION"C7F9"
VALUE"100.0PF"
PACK_TYPE"0402LF"
VOLTAGE"50V"
PART_NUMBER"A36095-026";
"A"
$PN"1"36;
"B"
$PN"2"39;
%"CAP"
"2","(-2500,2700)","2","mstr_discrete","I200";
;
CDS_SEC"1"
SEC_TYPE"0402LF"
CDS_LIB"mstr_discrete"
REUSE_ID"27"
BOM_COST"PVPP_KLM_VR"
SEC"1"
CDS_LOCATION"C7F12"
ROOM"PVPP_KLM_VR"
VALUE"2200PF"
TOLERANCE"10%"
LOCATION"C7F12"
PART_NUMBER"A36096-075"
PACK_TYPE"0402LF"
VOLTAGE"50V"
MATERIAL"X7R";
"A"
$PN"1"37;
"B"
$PN"2"39;
%"RES"
"1","(-1800,2700)","0","mstr_discrete","I201";
;
CDS_SEC"1"
REUSE_ID"13"
SEC"1"
SEC_TYPE"0402"
ROOM"PVPP_KLM_VR"
CDS_LOCATION"R7F18"
BOM_COST"PVPP_KLM_VR"
CDS_LIB"mstr_discrete"
PACK_TYPE"0402"
TOLERANCE"1.0%"
LOCATION"R7F18"
PART_NUMBER"G21796-242"
VALUE"7.87K"
MATERIAL"CHIP"
WATTAGE"1/16W";
"B"
$PN"2"36;
"A"
$PN"1"37;
%"CAP"
"1","(-5375,2625)","0","mstr_discrete","I202";
;
CDS_SEC"1"
SEC"1"
REUSE_ID"26"
SEC_TYPE"0603"
BOM_COST"PVPP_KLM_VR"
CDS_LOCATION"C3T11"
CDS_LIB"mstr_discrete"
ROOM"PVPP_KLM_VR"
PART_NUMBER"E15431-003"
TOLERANCE"10%"
VOLTAGE"6.3V"
VALUE"4.7UF"
LOCATION"C3T11"
PACK_TYPE"0603"
MATERIAL"X6S";
"A"
$PN"1"43;
"B"
$PN"2"23;
%"AGND_SCSI"
"1","(-5375,2325)","0","mstr_symbols","I203";
;
CDS_LIB"mstr_symbols"
ROOM"PVPP_KLM_VR"
BODY_TYPE"PLUMBING"
BOM_COST"PVPP_KLM_VR"
VOLTAGE"0.0V"
HDL_POWER"AGND_PVPP_ABC";
"A"23;
%"AGND_SCSI"
"1","(-5025,2950)","0","mstr_symbols","I204";
;
BODY_TYPE"PLUMBING"
CDS_LIB"mstr_symbols"
VOLTAGE"0.0V"
ROOM"PVPP_KLM_VR"
BOM_COST"PVPP_KLM_VR"
HDL_POWER"AGND_PVPP_ABC";
"A"24;
%"CAP_A"
"1","(-4775,3750)","0","dev_discrete","I205";
;
CDS_LOCATION"C7F6"
CDS_SEC"1"
SEC_TYPE"0402V"
SEC"1"
CDS_LIB"dev_discrete"
PART_NUMBER"A36096-030"
VALUE"0.1UF"
PACK_TYPE"0402V"
LOCATION"C7F6"
TOLERANCE"10%"
VOLTAGE"16V"
MATERIAL"X7R";
"B"
$PN"2"25;
"A"
$PN"1"42;
%"GND"
"1","(-4775,3525)","0","mstr_symbols","I206";
;
HDL_POWER"GND"
VOLTAGE"0"
SIZE"1B"
CDS_LIB"mstr_symbols"
BODY_TYPE"PLUMBING"
BOM_COST"PVPP_KLM_VR"
ROOM"PVPP_KLM_VR";
"A\NAC"25;
%"RES"
"1","(-3000,1225)","0","mstr_discrete","I208";
;
CDS_SEC"1"
ROOM"PVPP_KLM_VR"
SEC_TYPE"0402"
SEC"1"
CDS_LOCATION"R7F16"
CDS_LIB"mstr_discrete"
PACK_TYPE"0402"
PART_NUMBER"G21796-250"
LOCATION"R7F16"
TOLERANCE"1.0%"
MATERIAL"CHIP"
VALUE"22.1"
WATTAGE"1/16W";
"B"
$PN"2"40;
"A"
$PN"1"41;
%"CAP"
"1","(-6300,4375)","0","mstr_discrete","I209";
;
CDS_SEC"1"
SEC_TYPE"0805"
CDS_LOCATION"C7F5"
SEC"1"
CDS_LIB"mstr_discrete"
LOCATION"C7F5"
PART_NUMBER"C95333-007"
VALUE"10UF"
PACK_TYPE"0805"
VOLTAGE"16V"
TOLERANCE"10%"
MATERIAL"X6S";
"A"
$PN"1"42;
"B"
$PN"2"28;
%"CAP"
"1","(-5900,4375)","0","mstr_discrete","I210";
;
CDS_SEC"1"
SEC_TYPE"0805"
SEC"1"
CDS_LOCATION"C3T8"
CDS_LIB"mstr_discrete"
PART_NUMBER"C95333-007"
LOCATION"C3T8"
VALUE"10UF"
TOLERANCE"10%"
PACK_TYPE"0805"
VOLTAGE"16V"
MATERIAL"X6S";
"A"
$PN"1"42;
"B"
$PN"2"27;
%"CAP"
"1","(-5500,4375)","0","mstr_discrete","I211";
;
CDS_SEC"1"
SEC_TYPE"0805"
CDS_LOCATION"C3T14"
SEC"1"
CDS_LIB"mstr_discrete"
LOCATION"C3T14"
PART_NUMBER"C95333-007"
VALUE"10UF"
TOLERANCE"10%"
PACK_TYPE"0805"
VOLTAGE"16V"
MATERIAL"X6S";
"A"
$PN"1"42;
"B"
$PN"2"26;
%"GND"
"1","(-5500,4175)","0","mstr_symbols","I212";
;
HDL_POWER"GND"
CDS_LIB"mstr_symbols"
SIZE"1B"
VOLTAGE"0"
BODY_TYPE"PLUMBING"
ROOM"PVPP_KLM_VR"
BOM_COST"PVPP_KLM_VR";
"A\NAC"26;
%"GND"
"1","(-5900,4175)","0","mstr_symbols","I213";
;
SIZE"1B"
HDL_POWER"GND"
BODY_TYPE"PLUMBING"
CDS_LIB"mstr_symbols"
VOLTAGE"0"
ROOM"PVPP_KLM_VR"
BOM_COST"PVPP_KLM_VR";
"A\NAC"27;
%"GND"
"1","(-6300,4175)","0","mstr_symbols","I214";
;
HDL_POWER"GND"
SIZE"1B"
BODY_TYPE"PLUMBING"
CDS_LIB"mstr_symbols"
VOLTAGE"0"
ROOM"PVPP_KLM_VR"
BOM_COST"PVPP_KLM_VR";
"A\NAC"28;
%"CAP"
"1","(-5075,4375)","0","mstr_discrete","I215";
;
CDS_SEC"1"
SEC_TYPE"0805"
SEC"1"
CDS_LOCATION"C3T12"
CDS_LIB"mstr_discrete"
PART_NUMBER"C95333-007"
VOLTAGE"16V"
VALUE"10UF"
LOCATION"C3T12"
MATERIAL"X6S"
PACK_TYPE"0805"
TOLERANCE"10%";
"A"
$PN"1"42;
"B"
$PN"2"29;
%"GND"
"1","(-5075,4175)","0","mstr_symbols","I216";
;
HDL_POWER"GND"
VOLTAGE"0"
SIZE"1B"
CDS_LIB"mstr_symbols"
BODY_TYPE"PLUMBING"
ROOM"PVPP_KLM_VR"
BOM_COST"PVPP_KLM_VR";
"A\NAC"29;
%"CAPP"
"1","(-1075,3875)","0","mstr_discrete","I217";
;
CDS_SEC"1"
SEC_TYPE"7343"
SEC"1"
CDS_LOCATION"C4T3"
CDS_LIB"mstr_discrete"
LOCATION"C4T3"
PART_NUMBER"724613-067"
VALUE"220UF"
TOLERANCE"20%"
PACK_TYPE"7343"
VOLTAGE"4V"
MATERIAL"POSCAP";
"B"
$PN"2"14;
"A"
$PN"1"17;
%"RES"
"2","(-675,2875)","0","mstr_discrete","I218";
;
CDS_SEC"1"
SEC"1"
REUSE_ID"9"
SEC_TYPE"0402"
SPOF"TRUE"
BOM_COST"PVPP_KLM_VR"
ROOM"PVPP_KLM_VR"
CDS_LOCATION"R7F17"
CDS_LIB"mstr_discrete"
LOCATION"R7F17"
PART_NUMBER"G85996-004"
WATTAGE"1/16W"
TOLERANCE"0.1%"
VALUE"1.0K"
PACK_TYPE"0402"
MATERIAL"CHIP";
"A"
$PN"1"34;
"B"
$PN"2"35;
%"CAP"
"1","(-675,2325)","0","mstr_discrete","I219";
;
CDS_SEC"1"
SEC_TYPE"0402LF"
SPOF"TRUE"
REUSE_ID"26"
ROOM"PVPP_KLM_VR"
CDS_LOCATION"C7F13"
SEC"1"
CDS_LIB"mstr_discrete"
BOM_COST"PVPP_KLM_VR"
LOCATION"C7F13"
PART_NUMBER"A36096-075"
VALUE"2200PF"
PACK_TYPE"0402LF"
VOLTAGE"50V"
TOLERANCE"10%"
MATERIAL"X7R";
"A"
$PN"1"35;
"B"
$PN"2"36;
%"RES"
"1","(-5775,3075)","0","mstr_discrete","I220";
;
CDS_SEC"1"
ROOM"PVCCIN_CPU0_VR"
CDS_LOCATION"R7F9"
SEC"1"
SEC_TYPE"0402"
CDS_LIB"mstr_discrete"
LOCATION"R7F9"
PACK_TYPE"0402"
TOLERANCE"5%"
MATERIAL"CHIP"
PART_NUMBER"G21497-005"
VALUE"0.0"
WATTAGE"1/16W";
"B"
$PN"2"46;
"A"
$PN"1"30;
END.
